# S9S_MB_2U (Grand Teton) — schematic netlist excerpt (pin names and nets, part order shuffled) for the footprints in the layout excerpt that follows; sources: Cadence DE-HDL packaged netlist, KiCad conversion of 03242023_DA0F0TMBIJ0_F0T_Motherboard_J_brd_V01_OCP.brd

R3100  Q_RES  130 1% CHIP  pkg 0402LF  page 252 : A = LED_P3V3 ; B = P3V3
R1446  Q_RES  33.2 1% CHIP  pkg 0402LF  page 224 : A = PWRGD_PS_PWROK_PLD_ISO ; B = PWRGD_PS_PWROK_PLD_ISO_R

(kicad_pcb
	(version 20260206)
	(generator "pcbnew")
	(generator_version "10.0")
	(general
		(thickness 1.6)
		(legacy_teardrops no)
	)
	(paper "A4")
	(title_block
		(title "03242023_DA0F0TMBIJ0_F0T_Motherboard_J_brd_V01_OCP.brd")
		(comment 1 "Grand Teton / footprints 3324-3325 of 6105")
	)
	(layers
		(0 "F.Cu" signal "TOP")
		(4 "In1.Cu" signal "GND")
		(6 "In2.Cu" signal "IN1")
		(8 "In3.Cu" signal "GND1")
		(10 "In4.Cu" signal "IN2")
		(12 "In5.Cu" signal "GND2")
		(14 "In6.Cu" signal "IN3")
		(16 "In7.Cu" signal "GND3")
		(18 "In8.Cu" signal "VCC")
		(20 "In9.Cu" signal "VCC1")
		(22 "In10.Cu" signal "GND4")
		(24 "In11.Cu" signal "IN4")
		(26 "In12.Cu" signal "GND5")
		(28 "In13.Cu" signal "IN5")
		(30 "In14.Cu" signal "GND6")
		(32 "In15.Cu" signal "IN6")
		(34 "In16.Cu" signal "GND7")
		(2 "B.Cu" signal "BOTTOM")
		(9 "F.Adhes" user "F.Adhesive")
		(11 "B.Adhes" user "B.Adhesive")
		(13 "F.Paste" user "Package Geometry/Pastemask Top")
		(15 "B.Paste" user "Package Geometry/Pastemask Bottom")
		(5 "F.SilkS" user "Ref Des/Silkscreen Top")
		(7 "B.SilkS" user "Ref Des/Silkscreen Bottom")
		(1 "F.Mask" user "Board Geometry/Soldermask Top")
		(3 "B.Mask" user "Board Geometry/Soldermask Bottom")
		(17 "Dwgs.User" user "User.Drawings")
		(19 "Cmts.User" user "User.Comments")
		(21 "Eco1.User" user "User.Eco1")
		(23 "Eco2.User" user "User.Eco2")
		(25 "Edge.Cuts" user "Board Geometry/Outline")
		(27 "Margin" user)
		(31 "F.CrtYd" user "Package Geometry/Place Bound Top")
		(29 "B.CrtYd" user "Package Geometry/Place Bound Bottom")
		(35 "F.Fab" user "Ref Des/Assembly Top")
		(33 "B.Fab" user "Ref Des/Assembly Bottom")
	)
	(footprint ""
		(layer "F.Cu")
		(at 172.77588 -130.266948 -90)
		(property "Reference" "R1446"
			(at 0 0 270)
			(layer "F.SilkS")
			(hide yes)
			(effects
				(font
					(size 1.27 1.27)
				)
			)
		)
		(property "Value" ""
			(at 0 0 270)
			(layer "F.Fab")
			(effects
				(font
					(size 1.27 1.27)
				)
			)
		)
		(duplicate_pad_numbers_are_jumpers no)
		(fp_line
			(start -0.7874 0.4064)
			(end -0.7874 -0.4064)
			(stroke
				(width 0.1524)
				(type default)
			)
			(layer "F.SilkS")
		)
		(fp_line
			(start 0.7874 0.4064)
			(end -0.7874 0.4064)
			(stroke
				(width 0.1524)
				(type default)
			)
			(layer "F.SilkS")
		)
		(fp_line
			(start -0.7874 -0.4064)
			(end 0.7874 -0.4064)
			(stroke
				(width 0.1524)
				(type default)
			)
			(layer "F.SilkS")
		)
		(fp_line
			(start 0.7874 -0.4064)
			(end 0.7874 0.4064)
			(stroke
				(width 0.1524)
				(type default)
			)
			(layer "F.SilkS")
		)
		(fp_line
			(start -0.67945 0.3048)
			(end -0.67945 -0.305054)
			(stroke
				(width 0.1)
				(type default)
			)
			(layer "F.Fab")
		)
		(fp_line
			(start -0.12065 0.3048)
			(end -0.67945 0.3048)
			(stroke
				(width 0.1)
				(type default)
			)
			(layer "F.Fab")
		)
		(fp_line
			(start 0.120396 0.3048)
			(end 0.120396 0.2794)
			(stroke
				(width 0.1)
				(type default)
			)
			(layer "F.Fab")
		)
		(fp_line
			(start 0.67945 0.3048)
			(end 0.120396 0.3048)
			(stroke
				(width 0.1)
				(type default)
			)
			(layer "F.Fab")
		)
		(fp_line
			(start -0.12065 0.2794)
			(end -0.12065 0.3048)
			(stroke
				(width 0.1)
				(type default)
			)
			(layer "F.Fab")
		)
		(fp_line
			(start 0.120396 0.2794)
			(end -0.12065 0.2794)
			(stroke
				(width 0.1)
				(type default)
			)
			(layer "F.Fab")
		)
		(fp_line
			(start -0.12065 -0.2794)
			(end 0.12065 -0.2794)
			(stroke
				(width 0.1)
				(type default)
			)
			(layer "F.Fab")
		)
		(fp_line
			(start 0.12065 -0.2794)
			(end 0.12065 -0.3048)
			(stroke
				(width 0.1)
				(type default)
			)
			(layer "F.Fab")
		)
		(fp_line
			(start 0.12065 -0.3048)
			(end 0.67945 -0.3048)
			(stroke
				(width 0.1)
				(type default)
			)
			(layer "F.Fab")
		)
		(fp_line
			(start 0.67945 -0.3048)
			(end 0.67945 0.3048)
			(stroke
				(width 0.1)
				(type default)
			)
			(layer "F.Fab")
		)
		(fp_line
			(start -0.67945 -0.305054)
			(end -0.12065 -0.305054)
			(stroke
				(width 0.1)
				(type default)
			)
			(layer "F.Fab")
		)
		(fp_line
			(start -0.12065 -0.305054)
			(end -0.12065 -0.2794)
			(stroke
				(width 0.1)
				(type default)
			)
			(layer "F.Fab")
		)
		(pad "1" smd circle
			(at -0.40005 0 270)
			(size 0 0)
			(layers "F.Cu" "F.Mask" "F.Paste")
			(net "PWRGD_PS_PWROK_PLD_ISO")
		)
		(pad "2" smd circle
			(at 0.40005 0 270)
			(size 0 0)
			(layers "F.Cu" "F.Mask" "F.Paste")
			(net "PWRGD_PS_PWROK_PLD_ISO_R")
		)
	)
	(footprint ""
		(layer "F.Cu")
		(at 86.68893 -74.730356 -90)
		(property "Reference" "R3100"
			(at 0 0 270)
			(layer "F.SilkS")
			(hide yes)
			(effects
				(font
					(size 1.27 1.27)
				)
			)
		)
		(property "Value" ""
			(at 0 0 270)
			(layer "F.Fab")
			(effects
				(font
					(size 1.27 1.27)
				)
			)
		)
		(duplicate_pad_numbers_are_jumpers no)
		(fp_line
			(start -0.7874 0.4064)
			(end -0.7874 -0.4064)
			(stroke
				(width 0.1524)
				(type default)
			)
			(layer "F.SilkS")
		)
		(fp_line
			(start 0.7874 0.4064)
			(end -0.7874 0.4064)
			(stroke
				(width 0.1524)
				(type default)
			)
			(layer "F.SilkS")
		)
		(fp_line
			(start -0.7874 -0.4064)
			(end 0.7874 -0.4064)
			(stroke
				(width 0.1524)
				(type default)
			)
			(layer "F.SilkS")
		)
		(fp_line
			(start 0.7874 -0.4064)
			(end 0.7874 0.4064)
			(stroke
				(width 0.1524)
				(type default)
			)
			(layer "F.SilkS")
		)
		(fp_line
			(start -0.67945 0.3048)
			(end -0.67945 -0.305054)
			(stroke
				(width 0.1)
				(type default)
			)
			(layer "F.Fab")
		)
		(fp_line
			(start -0.12065 0.3048)
			(end -0.67945 0.3048)
			(stroke
				(width 0.1)
				(type default)
			)
			(layer "F.Fab")
		)
		(fp_line
			(start 0.120396 0.3048)
			(end 0.120396 0.2794)
			(stroke
				(width 0.1)
				(type default)
			)
			(layer "F.Fab")
		)
		(fp_line
			(start 0.67945 0.3048)
			(end 0.120396 0.3048)
			(stroke
				(width 0.1)
				(type default)
			)
			(layer "F.Fab")
		)
		(fp_line
			(start -0.12065 0.2794)
			(end -0.12065 0.3048)
			(stroke
				(width 0.1)
				(type default)
			)
			(layer "F.Fab")
		)
		(fp_line
			(start 0.120396 0.2794)
			(end -0.12065 0.2794)
			(stroke
				(width 0.1)
				(type default)
			)
			(layer "F.Fab")
		)
		(fp_line
			(start -0.12065 -0.2794)
			(end 0.12065 -0.2794)
			(stroke
				(width 0.1)
				(type default)
			)
			(layer "F.Fab")
		)
		(fp_line
			(start 0.12065 -0.2794)
			(end 0.12065 -0.3048)
			(stroke
				(width 0.1)
				(type default)
			)
			(layer "F.Fab")
		)
		(fp_line
			(start 0.12065 -0.3048)
			(end 0.67945 -0.3048)
			(stroke
				(width 0.1)
				(type default)
			)
			(layer "F.Fab")
		)
		(fp_line
			(start 0.67945 -0.3048)
			(end 0.67945 0.3048)
			(stroke
				(width 0.1)
				(type default)
			)
			(layer "F.Fab")
		)
		(fp_line
			(start -0.67945 -0.305054)
			(end -0.12065 -0.305054)
			(stroke
				(width 0.1)
				(type default)
			)
			(layer "F.Fab")
		)
		(fp_line
			(start -0.12065 -0.305054)
			(end -0.12065 -0.2794)
			(stroke
				(width 0.1)
				(type default)
			)
			(layer "F.Fab")
		)
		(pad "1" smd circle
			(at -0.40005 0 270)
			(size 0 0)
			(layers "F.Cu" "F.Mask" "F.Paste")
			(net "LED_P3V3")
		)
		(pad "2" smd circle
			(at 0.40005 0 270)
			(size 0 0)
			(layers "F.Cu" "F.Mask" "F.Paste")
			(net "P3V3")
		)
	)
)
